(kicad_sch
	(version 20250114)
	(generator "eeschema")
	(generator_version "9.0")
	(paper "A3")
	(title_block
		(title "RDIMM DDR5 Tester")
		(date "2026-05-21")
		(rev "2.2.0")
		(company "Antmicro")
		(comment 1 "www.antmicro.com")
	)
	(bus_alias "DDR5_RDIMM"
		(members "DQ[0..31]" "CA[0..6]" "CB[0..7]" "CK_P" "CK_N" "PAR" "DLBDQ"
			"DLBDQS" "~{ALERT}" "~{RESET}" "DQS0_P" "DQS0_N" "DQS1_P" "DQS1_N" "DQS2_P"
			"DQS2_N" "DQS3_P" "DQS3_N" "DQS4_P" "DQS4_N" "DQS5_P" "DQS5_N" "DQS6_P"
			"DQS6_N" "DQS7_P" "DQS7_N" "DQS8_P" "DQS8_N" "DQS9_P" "DQS9_N" "CS0_c"
			"CS1_c" "PWR_GOOD"
		)
	)
	(bus_alias "HyperBus"
		(members "~{CS}" "CK_P" "CK_N" "RWDS" "DQ[0..7]" "~{RESET}")
	)
	(bus_alias "I^{2}C"
		(members "SDA" "SCL")
	)
	(bus_alias "JTAG"
		(members "TDO" "TMS" "TCK" "RST" "TDI")
	)
	(bus_alias "PCIe_x8"
		(members "TXD0_P" "TXD0_N" "TXD1_P" "TXD1_N" "TXD2_P" "TXD2_N" "TXD3_P"
			"TXD3_N" "RXD0_P" "RXD0_N" "RXD1_P" "RXD1_N" "RXD2_P" "RXD2_N" "RXD3_P"
			"RXD3_N" "CLK_P" "CLK_N" "TXD4_P" "TXD4_N" "TXD5_P" "TXD5_N" "TXD6_P"
			"TXD6_N" "TXD7_P" "TXD7_N" "RXD4_P" "RXD4_N" "RXD5_P" "RXD5_N" "RXD6_P"
			"RXD6_N" "RXD7_P" "RXD7_N"
		)
	)
	(bus_alias "QSPI"
		(members "IO[0..3]" "~{CS}" "SCK")
	)
	(bus_alias "RGMII"
		(members "~{RESET}" "~{INT}" "MDC" "MDIO" "TX_CTL" "TXD[0..3]" "TXC" "RX_CTL"
			"RXD[0..3]" "RXC" "REF_CLK"
		)
	)
	(bus_alias "SDIO"
		(members "DAT[0..3]" "CMD" "CLK" "CD")
	)
	(bus_alias "TMDS"
		(members "D0_P" "D0_N" "D1_P" "D1_N" "D2_P" "D2_N" "CLK_P" "CLK_N")
	)
	(bus_alias "UART"
		(members "TX" "RX")
	)
	(bus_alias "USB"
		(members "D+")
	)
	(text "FPGA\nArtix US+\nXCAU25P"
		(exclude_from_sim no)
		(at 201.295 141.605 0)
		(effects
			(font
				(size 2.54 2.54)
			)
			(justify left bottom)
		)
	)
	(text "JTAG"
		(exclude_from_sim no)
		(at 177.8 124.46 0)
		(effects
			(font
				(size 1.27 1.27)
			)
			(justify left bottom)
		)
	)
	(text "Mechanical"
		(exclude_from_sim no)
		(at 254 256.54 0)
		(effects
			(font
				(size 2 2)
				(thickness 0.4)
				(bold yes)
			)
			(justify left bottom)
		)
	)
	(text "Status LEDs"
		(exclude_from_sim no)
		(at 171.45 127 0)
		(effects
			(font
				(size 1.27 1.27)
			)
			(justify left bottom)
		)
	)
	(text "RDIMM DDR5 Tester"
		(exclude_from_sim no)
		(at 181.61 33.02 0)
		(effects
			(font
				(size 3.9878 3.9878)
				(thickness 0.7976)
				(bold yes)
			)
			(justify left bottom)
		)
	)
	(junction
		(at 142.24 217.17)
		(diameter 0)
		(color 0 0 0 0)
	)
	(junction
		(at 134.62 195.58)
		(diameter 0)
		(color 0 0 0 0)
	)
	(bus
		(pts
			(xy 288.29 93.98) (xy 288.29 44.45)
		)
		(stroke
			(width 0)
			(type default)
		)
	)
	(bus
		(pts
			(xy 116.84 87.63) (xy 116.84 41.91)
		)
		(stroke
			(width 0)
			(type default)
		)
	)
	(bus
		(pts
			(xy 139.7 219.71) (xy 139.7 238.76)
		)
		(stroke
			(width 0)
			(type default)
		)
	)
	(bus
		(pts
			(xy 134.62 102.87) (xy 134.62 195.58)
		)
		(stroke
			(width 0)
			(type default)
		)
	)
	(bus
		(pts
			(xy 273.05 90.17) (xy 281.94 90.17)
		)
		(stroke
			(width 0)
			(type default)
		)
	)
	(bus
		(pts
			(xy 109.22 148.59) (xy 146.05 148.59)
		)
		(stroke
			(width 0)
			(type default)
		)
	)
	(bus
		(pts
			(xy 290.83 41.91) (xy 290.83 96.52)
		)
		(stroke
			(width 0)
			(type default)
		)
	)
	(bus
		(pts
			(xy 273.05 152.4) (xy 288.29 152.4)
		)
		(stroke
			(width 0)
			(type default)
		)
	)
	(bus
		(pts
			(xy 142.24 111.76) (xy 142.24 217.17)
		)
		(stroke
			(width 0)
			(type default)
		)
	)
	(bus
		(pts
			(xy 121.92 87.63) (xy 146.05 87.63)
		)
		(stroke
			(width 0)
			(type default)
		)
	)
	(bus
		(pts
			(xy 116.84 41.91) (xy 290.83 41.91)
		)
		(stroke
			(width 0)
			(type default)
		)
	)
	(bus
		(pts
			(xy 288.29 152.4) (xy 288.29 241.3)
		)
		(stroke
			(width 0)
			(type default)
		)
	)
	(bus
		(pts
			(xy 64.77 246.38) (xy 339.09 246.38)
		)
		(stroke
			(width 0)
			(type default)
		)
	)
	(bus
		(pts
			(xy 127 180.34) (xy 127 158.75)
		)
		(stroke
			(width 0)
			(type default)
		)
	)
	(bus
		(pts
			(xy 119.38 44.45) (xy 119.38 116.84)
		)
		(stroke
			(width 0)
			(type default)
		)
	)
	(bus
		(pts
			(xy 279.4 87.63) (xy 273.05 87.63)
		)
		(stroke
			(width 0)
			(type default)
		)
	)
	(bus
		(pts
			(xy 64.77 53.34) (xy 144.78 53.34)
		)
		(stroke
			(width 0)
			(type default)
		)
	)
	(bus
		(pts
			(xy 119.38 116.84) (xy 109.22 116.84)
		)
		(stroke
			(width 0)
			(type default)
		)
	)
	(bus
		(pts
			(xy 71.12 180.34) (xy 64.77 180.34)
		)
		(stroke
			(width 0)
			(type default)
		)
	)
	(bus
		(pts
			(xy 109.22 87.63) (xy 116.84 87.63)
		)
		(stroke
			(width 0)
			(type default)
		)
	)
	(bus
		(pts
			(xy 142.24 217.17) (xy 142.24 236.22)
		)
		(stroke
			(width 0)
			(type default)
		)
	)
	(bus
		(pts
			(xy 139.7 238.76) (xy 285.75 238.76)
		)
		(stroke
			(width 0)
			(type default)
		)
	)
	(bus
		(pts
			(xy 273.05 64.77) (xy 279.4 64.77)
		)
		(stroke
			(width 0)
			(type default)
		)
	)
	(bus
		(pts
			(xy 129.54 97.79) (xy 129.54 190.5)
		)
		(stroke
			(width 0)
			(type default)
		)
	)
	(bus
		(pts
			(xy 134.62 102.87) (xy 146.05 102.87)
		)
		(stroke
			(width 0)
			(type default)
		)
	)
	(bus
		(pts
			(xy 283.21 157.48) (xy 273.05 157.48)
		)
		(stroke
			(width 0)
			(type default)
		)
	)
	(polyline
		(pts
			(xy 144.78 200.66) (xy 274.32 200.66)
		)
		(stroke
			(width 0)
			(type dash)
		)
	)
	(bus
		(pts
			(xy 276.86 67.31) (xy 273.05 67.31)
		)
		(stroke
			(width 0)
			(type default)
		)
	)
	(bus
		(pts
			(xy 137.16 222.25) (xy 109.22 222.25)
		)
		(stroke
			(width 0)
			(type default)
		)
	)
	(bus
		(pts
			(xy 132.08 100.33) (xy 146.05 100.33)
		)
		(stroke
			(width 0)
			(type default)
		)
	)
	(bus
		(pts
			(xy 278.13 208.28) (xy 274.32 208.28)
		)
		(stroke
			(width 0)
			(type default)
		)
	)
	(bus
		(pts
			(xy 276.86 67.31) (xy 276.86 85.09)
		)
		(stroke
			(width 0)
			(type default)
		)
	)
	(polyline
		(pts
			(xy 144.78 78.74) (xy 274.32 78.74)
		)
		(stroke
			(width 0)
			(type dash)
		)
	)
	(polyline
		(pts
			(xy 274.32 200.66) (xy 274.32 78.74)
		)
		(stroke
			(width 0)
			(type dash)
		)
	)
	(bus
		(pts
			(xy 124.46 90.17) (xy 146.05 90.17)
		)
		(stroke
			(width 0)
			(type default)
		)
	)
	(bus
		(pts
			(xy 139.7 219.71) (xy 109.22 219.71)
		)
		(stroke
			(width 0)
			(type default)
		)
	)
	(bus
		(pts
			(xy 134.62 195.58) (xy 146.05 195.58)
		)
		(stroke
			(width 0)
			(type default)
		)
	)
	(bus
		(pts
			(xy 285.75 154.94) (xy 273.05 154.94)
		)
		(stroke
			(width 0)
			(type default)
		)
	)
	(bus
		(pts
			(xy 334.01 226.06) (xy 339.09 226.06)
		)
		(stroke
			(width 0)
			(type default)
		)
	)
	(bus
		(pts
			(xy 109.22 180.34) (xy 127 180.34)
		)
		(stroke
			(width 0)
			(type default)
		)
	)
	(bus
		(pts
			(xy 127 92.71) (xy 146.05 92.71)
		)
		(stroke
			(width 0)
			(type default)
		)
	)
	(bus
		(pts
			(xy 109.22 195.58) (xy 134.62 195.58)
		)
		(stroke
			(width 0)
			(type default)
		)
	)
	(bus
		(pts
			(xy 109.22 217.17) (xy 142.24 217.17)
		)
		(stroke
			(width 0)
			(type default)
		)
	)
	(bus
		(pts
			(xy 137.16 222.25) (xy 137.16 241.3)
		)
		(stroke
			(width 0)
			(type default)
		)
	)
	(bus
		(pts
			(xy 139.7 109.22) (xy 146.05 109.22)
		)
		(stroke
			(width 0)
			(type default)
		)
	)
	(bus
		(pts
			(xy 109.22 158.75) (xy 127 158.75)
		)
		(stroke
			(width 0)
			(type default)
		)
	)
	(bus
		(pts
			(xy 273.05 194.31) (xy 278.13 194.31)
		)
		(stroke
			(width 0)
			(type default)
		)
	)
	(bus
		(pts
			(xy 279.4 64.77) (xy 279.4 87.63)
		)
		(stroke
			(width 0)
			(type default)
		)
	)
	(bus
		(pts
			(xy 109.22 130.81) (xy 146.05 130.81)
		)
		(stroke
			(width 0)
			(type default)
		)
	)
	(bus
		(pts
			(xy 276.86 85.09) (xy 273.05 85.09)
		)
		(stroke
			(width 0)
			(type default)
		)
	)
	(bus
		(pts
			(xy 290.83 99.06) (xy 290.83 243.84)
		)
		(stroke
			(width 0)
			(type default)
		)
	)
	(bus
		(pts
			(xy 288.29 241.3) (xy 137.16 241.3)
		)
		(stroke
			(width 0)
			(type default)
		)
	)
	(bus
		(pts
			(xy 121.92 151.13) (xy 121.92 87.63)
		)
		(stroke
			(width 0)
			(type default)
		)
	)
	(bus
		(pts
			(xy 283.21 157.48) (xy 283.21 236.22)
		)
		(stroke
			(width 0)
			(type default)
		)
	)
	(bus
		(pts
			(xy 124.46 153.67) (xy 124.46 90.17)
		)
		(stroke
			(width 0)
			(type default)
		)
	)
	(bus
		(pts
			(xy 64.77 180.34) (xy 64.77 53.34)
		)
		(stroke
			(width 0)
			(type default)
		)
	)
	(bus
		(pts
			(xy 109.22 151.13) (xy 121.92 151.13)
		)
		(stroke
			(width 0)
			(type default)
		)
	)
	(bus
		(pts
			(xy 132.08 100.33) (xy 132.08 193.04)
		)
		(stroke
			(width 0)
			(type default)
		)
	)
	(bus
		(pts
			(xy 281.94 62.23) (xy 273.05 62.23)
		)
		(stroke
			(width 0)
			(type default)
		)
	)
	(bus
		(pts
			(xy 290.83 99.06) (xy 273.05 99.06)
		)
		(stroke
			(width 0)
			(type default)
		)
	)
	(bus
		(pts
			(xy 109.22 153.67) (xy 124.46 153.67)
		)
		(stroke
			(width 0)
			(type default)
		)
	)
	(bus
		(pts
			(xy 278.13 194.31) (xy 278.13 208.28)
		)
		(stroke
			(width 0)
			(type default)
		)
	)
	(bus
		(pts
			(xy 109.22 193.04) (xy 132.08 193.04)
		)
		(stroke
			(width 0)
			(type default)
		)
	)
	(bus
		(pts
			(xy 127 156.21) (xy 127 92.71)
		)
		(stroke
			(width 0)
			(type default)
		)
	)
	(bus
		(pts
			(xy 339.09 226.06) (xy 339.09 246.38)
		)
		(stroke
			(width 0)
			(type default)
		)
	)
	(bus
		(pts
			(xy 137.16 106.68) (xy 137.16 212.09)
		)
		(stroke
			(width 0)
			(type default)
		)
	)
	(bus
		(pts
			(xy 288.29 44.45) (xy 119.38 44.45)
		)
		(stroke
			(width 0)
			(type default)
		)
	)
	(bus
		(pts
			(xy 139.7 214.63) (xy 139.7 109.22)
		)
		(stroke
			(width 0)
			(type default)
		)
	)
	(bus
		(pts
			(xy 134.62 243.84) (xy 134.62 226.06)
		)
		(stroke
			(width 0)
			(type default)
		)
	)
	(bus
		(pts
			(xy 146.05 111.76) (xy 142.24 111.76)
		)
		(stroke
			(width 0)
			(type default)
		)
	)
	(bus
		(pts
			(xy 290.83 96.52) (xy 273.05 96.52)
		)
		(stroke
			(width 0)
			(type default)
		)
	)
	(bus
		(pts
			(xy 129.54 190.5) (xy 109.22 190.5)
		)
		(stroke
			(width 0)
			(type default)
		)
	)
	(bus
		(pts
			(xy 134.62 226.06) (xy 109.22 226.06)
		)
		(stroke
			(width 0)
			(type default)
		)
	)
	(bus
		(pts
			(xy 288.29 93.98) (xy 273.05 93.98)
		)
		(stroke
			(width 0)
			(type default)
		)
	)
	(bus
		(pts
			(xy 285.75 238.76) (xy 285.75 154.94)
		)
		(stroke
			(width 0)
			(type default)
		)
	)
	(bus
		(pts
			(xy 64.77 194.31) (xy 64.77 246.38)
		)
		(stroke
			(width 0)
			(type default)
		)
	)
	(bus
		(pts
			(xy 134.62 243.84) (xy 290.83 243.84)
		)
		(stroke
			(width 0)
			(type default)
		)
	)
	(bus
		(pts
			(xy 146.05 106.68) (xy 137.16 106.68)
		)
		(stroke
			(width 0)
			(type default)
		)
	)
	(polyline
		(pts
			(xy 144.78 78.74) (xy 144.78 200.66)
		)
		(stroke
			(width 0)
			(type dash)
		)
	)
	(bus
		(pts
			(xy 71.12 194.31) (xy 64.77 194.31)
		)
		(stroke
			(width 0)
			(type default)
		)
	)
	(bus
		(pts
			(xy 109.22 212.09) (xy 137.16 212.09)
		)
		(stroke
			(width 0)
			(type default)
		)
	)
	(bus
		(pts
			(xy 142.24 236.22) (xy 283.21 236.22)
		)
		(stroke
			(width 0)
			(type default)
		)
	)
	(bus
		(pts
			(xy 109.22 156.21) (xy 127 156.21)
		)
		(stroke
			(width 0)
			(type default)
		)
	)
	(bus
		(pts
			(xy 281.94 90.17) (xy 281.94 62.23)
		)
		(stroke
			(width 0)
			(type default)
		)
	)
	(bus
		(pts
			(xy 109.22 214.63) (xy 139.7 214.63)
		)
		(stroke
			(width 0)
			(type default)
		)
	)
	(bus
		(pts
			(xy 146.05 97.79) (xy 129.54 97.79)
		)
		(stroke
			(width 0)
			(type default)
		)
	)
	(symbol
		(lib_id "antmicroMechanicalParts:Heatsink_ATS-61500R-C2-R0")
		(at 255.27 262.89 0)
		(unit 1)
		(exclude_from_sim no)
		(in_bom yes)
		(on_board yes)
		(dnp no)
		(fields_autoplaced yes)
		(property "Reference" "A1"
			(at 261.62 263.8425 0)
			(effects
				(font
					(size 1.27 1.27)
					(thickness 0.15)
				)
				(justify left)
			)
		)
		(property "Value" "Heatsink_ATS-61500R-C2-R0"
			(at 261.62 266.3825 0)
			(effects
				(font
					(size 1.27 1.27)
					(thickness 0.15)
				)
				(justify left)
			)
		)
		(property "Footprint" "antmicro-footprints:Heatsink_ATS-61500R-C2-R0"
			(at 273.05 270.51 0)
			(effects
				(font
					(size 1.27 1.27)
					(thickness 0.15)
				)
				(justify left bottom)
				(hide yes)
			)
		)
		(property "Datasheet" "https://www.qats.com/DataSheet/ATS-61500-Series-C2-R0"
			(at 273.05 273.05 0)
			(effects
				(font
					(size 1.27 1.27)
					(thickness 0.15)
				)
				(justify left bottom)
				(hide yes)
			)
		)
		(property "Description" ""
			(at 255.27 262.89 0)
			(effects
				(font
					(size 1.27 1.27)
				)
				(hide yes)
			)
		)
		(property "MPN" "ATS-61500R-C2-R0"
			(at 273.05 275.59 0)
			(effects
				(font
					(size 1.27 1.27)
					(thickness 0.15)
				)
				(justify left bottom)
				(hide yes)
			)
		)
		(property "Manufacturer" "Advanced Thermal Solutions"
			(at 273.05 278.13 0)
			(effects
				(font
					(size 1.27 1.27)
					(thickness 0.15)
				)
				(justify left bottom)
				(hide yes)
			)
		)
		(property "Author" "Antmicro"
			(at 273.05 280.67 0)
			(effects
				(font
					(size 1.27 1.27)
					(thickness 0.15)
				)
				(justify left bottom)
				(hide yes)
			)
		)
		(property "License" "Apache-2.0"
			(at 273.05 283.21 0)
			(effects
				(font
					(size 1.27 1.27)
					(thickness 0.15)
				)
				(justify left bottom)
				(hide yes)
			)
		)
		(instances
			(project "data-center-rdimm-ddr5-tester"
				(path ""
					(reference "A1")
					(unit 1)
				)
			)
		)
	)
	(symbol
		(lib_id "antmicroMechanicalParts:Lightpipe_Mentor_1296.2013")
		(at 260.35 276.86 0)
		(unit 1)
		(exclude_from_sim no)
		(in_bom yes)
		(on_board yes)
		(dnp no)
		(fields_autoplaced yes)
		(property "Reference" "H2"
			(at 266.192 275.3944 0)
			(effects
				(font
					(size 1.27 1.27)
					(thickness 0.15)
				)
				(justify left)
			)
		)
		(property "Value" "Lightpipe_Mentor_1296.2013"
			(at 266.192 277.9181 0)
			(effects
				(font
					(size 1.27 1.27)
					(thickness 0.15)
				)
				(justify left)
			)
		)
		(property "Footprint" "antmicro-footprints:Mech_Lightpipe_Mentor_1296.2013"
			(at 280.67 284.48 0)
			(effects
				(font
					(size 1.27 1.27)
					(thickness 0.15)
				)
				(justify left bottom)
				(hide yes)
			)
		)
		(property "Datasheet" "https://docs.rs-online.com/e47b/0900766b813f6efb.pdf"
			(at 280.67 287.02 0)
			(effects
				(font
					(size 1.27 1.27)
					(thickness 0.15)
				)
				(justify left bottom)
				(hide yes)
			)
		)
		(property "Description" ""
			(at 260.35 276.86 0)
			(effects
				(font
					(size 1.27 1.27)
				)
				(hide yes)
			)
		)
		(property "Manufacturer" "Mentor Worldwide"
			(at 280.67 289.56 0)
			(effects
				(font
					(size 1.27 1.27)
					(thickness 0.15)
				)
				(justify left bottom)
				(hide yes)
			)
		)
		(property "MPN" "1296.2013"
			(at 280.67 292.1 0)
			(effects
				(font
					(size 1.27 1.27)
					(thickness 0.15)
				)
				(justify left bottom)
				(hide yes)
			)
		)
		(property "Author" "Antmicro"
			(at 280.67 294.64 0)
			(effects
				(font
					(size 1.27 1.27)
					(thickness 0.15)
				)
				(justify left bottom)
				(hide yes)
			)
		)
		(property "License" "Apache-2.0"
			(at 280.67 297.18 0)
			(effects
				(font
					(size 1.27 1.27)
					(thickness 0.15)
				)
				(justify left bottom)
				(hide yes)
			)
		)
		(instances
			(project "data-center-rdimm-ddr5-tester"
				(path ""
					(reference "H2")
					(unit 1)
				)
			)
		)
	)
	(sheet
		(at 71.12 82.55)
		(size 38.1 19.05)
		(exclude_from_sim no)
		(in_bom yes)
		(on_board yes)
		(dnp no)
		(fields_autoplaced yes)
		(stroke
			(width 0)
			(type solid)
		)
		(fill
			(color 0 0 0 0.0000)
		)
		(property "Sheetname" "Ethernet"
			(at 71.12 81.8384 0)
			(effects
				(font
					(size 1.27 1.27)
				)
				(justify left bottom)
			)
		)
		(property "Sheetfile" "ethernet.kicad_sch"
			(at 71.12 102.1846 0)
			(effects
				(font
					(size 1.27 1.27)
				)
				(justify left top)
			)
		)
		(pin "ETH{RGMII}" bidirectional
			(at 109.22 87.63 0)
			(effects
				(font
					(size 1.27 1.27)
				)
				(justify right)
			)
		)
		(instances
			(project "data-center-rdimm-ddr5-tester"
				(path ""
					(page "8")
				)
			)
		)
	)
	(sheet
		(at 146.05 120.65)
		(size 38.1 76.2)
		(exclude_from_sim no)
		(in_bom yes)
		(on_board yes)
		(dnp no)
		(fields_autoplaced yes)
		(stroke
			(width 0)
			(type solid)
		)
		(fill
			(color 0 0 0 0.0000)
		)
		(property "Sheetname" "FPGA Config"
			(at 146.05 119.9384 0)
			(effects
				(font
					(size 1.27 1.27)
				)
				(justify left bottom)
			)
		)
		(property "Sheetfile" "fpga-config.kicad_sch"
			(at 146.05 197.4346 0)
			(effects
				(font
					(size 1.27 1.27)
				)
				(justify left top)
			)
		)
		(pin "JTAG{JTAG}" bidirectional
			(at 146.05 148.59 180)
			(effects
				(font
					(size 1.27 1.27)
				)
				(justify left)
			)
		)
		(pin "FLASH{QSPI}" bidirectional
			(at 146.05 130.81 180)
			(effects
				(font
					(size 1.27 1.27)
				)
				(justify left)
			)
		)
		(pin "FPGA_PWR{I^{2}C}" bidirectional
			(at 146.05 195.58 180)
			(effects
				(font
					(size 1.27 1.27)
				)
				(justify left)
			)
		)
		(instances
			(project "data-center-rdimm-ddr5-tester"
				(path ""
					(page "3")
				)
			)
		)
	)
	(sheet
		(at 71.12 114.3)
		(size 38.1 19.05)
		(exclude_from_sim no)
		(in_bom yes)
		(on_board yes)
		(dnp no)
		(fields_autoplaced yes)
		(stroke
			(width 0)
			(type solid)
		)
		(fill
			(color 0 0 0 0.0000)
		)
		(property "Sheetname" "HyperRAM + QSPI Flash"
			(at 71.12 113.5884 0)
			(effects
				(font
					(size 1.27 1.27)
				)
				(justify left bottom)
			)
		)
		(property "Sheetfile" "hyperram-flash.kicad_sch"
			(at 71.12 133.9346 0)
			(effects
				(font
					(size 1.27 1.27)
				)
				(justify left top)
			)
		)
		(pin "HyperRAM{HyperBus}" bidirectional
			(at 109.22 116.84 0)
			(effects
				(font
					(size 1.27 1.27)
				)
				(justify right)
			)
		)
		(pin "FLASH{QSPI}" bidirectional
			(at 109.22 130.81 0)
			(effects
				(font
					(size 1.27 1.27)
				)
				(justify right)
			)
		)
		(instances
			(project "data-center-rdimm-ddr5-tester"
				(path ""
					(page "2")
				)
			)
		)
	)
	(sheet
		(at 234.95 114.3)
		(size 38.1 19.05)
		(exclude_from_sim no)
		(in_bom yes)
		(on_board yes)
		(dnp no)
		(fields_autoplaced yes)
		(stroke
			(width 0)
			(type solid)
		)
		(fill
			(color 0 0 0 0.0000)
		)
		(property "Sheetname" "FPGA power"
			(at 234.95 113.5884 0)
			(effects
				(font
					(size 1.27 1.27)
				)
				(justify left bottom)
			)
		)
		(property "Sheetfile" "fpga-power.kicad_sch"
			(at 234.95 133.9346 0)
			(effects
				(font
					(size 1.27 1.27)
				)
				(justify left top)
			)
		)
		(instances
			(project "data-center-rdimm-ddr5-tester"
				(path ""
					(page "5")
				)
			)
		)
	)
	(sheet
		(at 71.12 146.05)
		(size 38.1 19.05)
		(exclude_from_sim no)
		(in_bom yes)
		(on_board yes)
		(dnp no)
		(fields_autoplaced yes)
		(stroke
			(width 0)
			(type solid)
		)
		(fill
			(color 0 0 0 0.0000)
		)
		(property "Sheetname" "Debug FTDI + VNA"
			(at 71.12 145.3384 0)
			(effects
				(font
					(size 1.27 1.27)
				)
				(justify left bottom)
			)
		)
		(property "Sheetfile" "debug-ftdi.kicad_sch"
			(at 71.12 165.6846 0)
			(effects
				(font
					(size 1.27 1.27)
				)
				(justify left top)
			)
		)
		(pin "UART1{UART}" bidirectional
			(at 109.22 156.21 0)
			(effects
				(font
					(size 1.27 1.27)
				)
				(justify right)
			)
		)
		(pin "AUX{JTAG}" bidirectional
			(at 109.22 151.13 0)
			(effects
				(font
					(size 1.27 1.27)
				)
				(justify right)
			)
		)
		(pin "UART0{UART}" bidirectional
			(at 109.22 153.67 0)
			(effects
				(font
					(size 1.27 1.27)
				)
				(justify right)
			)
		)
		(pin "JTAG{JTAG}" bidirectional
			(at 109.22 148.59 0)
			(effects
				(font
					(size 1.27 1.27)
				)
				(justify right)
			)
		)
		(pin "FTDI{I^{2}C}" bidirectional
			(at 109.22 158.75 0)
			(effects
				(font
					(size 1.27 1.27)
				)
				(justify right)
			)
		)
		(instances
			(project "data-center-rdimm-ddr5-tester"
				(path ""
					(page "6")
				)
			)
		)
	)
	(sheet
		(at 295.91 50.8)
		(size 38.1 177.8)
		(exclude_from_sim no)
		(in_bom yes)
		(on_board yes)
		(dnp no)
		(fields_autoplaced yes)
		(stroke
			(width 0)
			(type solid)
		)
		(fill
			(color 0 0 0 0.0000)
		)
		(property "Sheetname" "Supply"
			(at 295.91 50.0884 0)
			(effects
				(font
					(size 1.27 1.27)
				)
				(justify left bottom)
			)
		)
		(property "Sheetfile" "supply.kicad_sch"
			(at 295.91 229.1846 0)
			(effects
				(font
					(size 1.27 1.27)
				)
				(justify left top)
			)
		)
		(pin "PWR{I^{2}C}" bidirectional
			(at 334.01 226.06 0)
			(effects
				(font
					(size 1.27 1.27)
				)
				(justify right)
			)
		)
		(instances
			(project "data-center-rdimm-ddr5-tester"
				(path ""
					(page "10")
				)
			)
		)
	)
	(sheet
		(at 144.78 50.8)
		(size 128.27 19.05)
		(exclude_from_sim no)
		(in_bom yes)
		(on_board yes)
		(dnp no)
		(fields_autoplaced yes)
		(stroke
			(width 0)
			(type solid)
		)
		(fill
			(color 0 0 0 0.0000)
		)
		(property "Sheetname" "DDR5 RDIMM"
			(at 144.78 50.0884 0)
			(effects
				(font
					(size 1.27 1.27)
				)
				(justify left bottom)
			)
		)
		(property "Sheetfile" "ddr5-rdimm.kicad_sch"
			(at 144.78 70.4346 0)
			(effects
				(font
					(size 1.27 1.27)
				)
				(justify left top)
			)
		)
		(pin "DDR{I^{2}C}" bidirectional
			(at 144.78 53.34 180)
			(effects
				(font
					(size 1.27 1.27)
				)
				(justify left)
			)
		)
		(pin "CTRL{DDR5_RDIMM}" input
			(at 273.05 67.31 0)
			(effects
				(font
					(size 1.27 1.27)
				)
				(justify right)
			)
		)
		(pin "B{DDR5_RDIMM}" input
			(at 273.05 64.77 0)
			(effects
				(font
					(size 1.27 1.27)
				)
				(justify right)
			)
		)
		(pin "A{DDR5_RDIMM}" input
			(at 273.05 62.23 0)
			(effects
				(font
					(size 1.27 1.27)
				)
				(justify right)
			)
		)
		(instances
			(project "data-center-rdimm-ddr5-tester"
				(path ""
					(page "4")
				)
			)
		)
	)
	(sheet
		(at 210.82 82.55)
		(size 62.23 19.05)
		(exclude_from_sim no)
		(in_bom yes)
		(on_board yes)
		(dnp no)
		(fields_autoplaced yes)
		(stroke
			(width 0)
			(type solid)
		)
		(fill
			(color 0 0 0 0.0000)
		)
		(property "Sheetname" "FPGA banks HP"
			(at 210.82 81.8384 0)
			(effects
				(font
					(size 1.27 1.27)
				)
				(justify left bottom)
			)
		)
		(property "Sheetfile" "fpga-hp-banks.kicad_sch"
			(at 210.82 102.1846 0)
			(effects
				(font
					(size 1.27 1.27)
				)
				(justify left top)
			)
		)
		(pin "B{DDR5_RDIMM}" input
			(at 273.05 87.63 0)
			(effects
				(font
					(size 1.27 1.27)
				)
				(justify right)
			)
		)
		(pin "A{DDR5_RDIMM}" input
			(at 273.05 90.17 0)
			(effects
				(font
					(size 1.27 1.27)
				)
				(justify right)
			)
		)
		(pin "CTRL{DDR5_RDIMM}" input
			(at 273.05 85.09 0)
			(effects
				(font
					(size 1.27 1.27)
				)
				(justify right)
			)
		)
		(pin "ETH{RGMII}" bidirectional
			(at 273.05 96.52 0)
			(effects
				(font
					(size 1.27 1.27)
				)
				(justify right)
			)
		)
		(pin "HyperRAM{HyperBus}" bidirectional
			(at 273.05 93.98 0)
			(effects
				(font
					(size 1.27 1.27)
				)
				(justify right)
			)
		)
		(pin "SD{SDIO}" bidirectional
			(at 273.05 99.06 0)
			(effects
				(font
					(size 1.27 1.27)
				)
				(justify right)
			)
		)
		(instances
			(project "data-center-rdimm-ddr5-tester"
				(path ""
					(page "9")
				)
			)
		)
	)
	(sheet
		(at 146.05 82.55)
		(size 38.1 30.48)
		(exclude_from_sim no)
		(in_bom yes)
		(on_board yes)
		(dnp no)
		(fields_autoplaced yes)
		(stroke
			(width 0.1524)
			(type solid)
		)
		(fill
			(color 0 0 0 0.0000)
		)
		(property "Sheetname" "FPGA banks HD"
			(at 146.05 81.8384 0)
			(effects
				(font
					(size 1.27 1.27)
				)
				(justify left bottom)
			)
		)
		(property "Sheetfile" "fpga-hd-banks.kicad_sch"
			(at 146.05 113.6146 0)
			(effects
				(font
					(size 1.27 1.27)
				)
				(justify left top)
			)
		)
		(pin "FPGA_PWR{I^{2}C}" bidirectional
			(at 146.05 102.87 180)
			(effects
				(font
					(size 1.27 1.27)
				)
				(justify left)
			)
		)
		(pin "FPGA_DDR{I^{2}C}" bidirectional
			(at 146.05 100.33 180)
			(effects
				(font
					(size 1.27 1.27)
				)
				(justify left)
			)
		)
		(pin "AUX{JTAG}" bidirectional
			(at 146.05 87.63 180)
			(effects
				(font
					(size 1.27 1.27)
				)
				(justify left)
			)
		)
		(pin "UART1{UART}" bidirectional
			(at 146.05 92.71 180)
			(effects
				(font
					(size 1.27 1.27)
				)
				(justify left)
			)
		)
		(pin "HDMI_OUT_I2C{I^{2}C}" bidirectional
			(at 146.05 109.22 180)
			(effects
				(font
					(size 1.27 1.27)
				)
				(justify left)
			)
		)
		(pin "HDMI_CTL{I^{2}C}" bidirectional
			(at 146.05 111.76 180)
			(effects
				(font
					(size 1.27 1.27)
				)
				(justify left)
			)
		)
		(pin "UART0{UART}" bidirectional
			(at 146.05 90.17 180)
			(effects
				(font
					(size 1.27 1.27)
				)
				(justify left)
			)
		)
		(pin "HDMI_IN_I2C{I^{2}C}" bidirectional
			(at 146.05 106.68 180)
			(effects
				(font
					(size 1.27 1.27)
				)
				(justify left)
			)
		)
		(pin "FPGA_I3C{I^{2}C}" bidirectional
			(at 146.05 97.79 180)
			(effects
				(font
					(size 1.27 1.27)
				)
				(justify left)
			)
		)
		(instances
			(project "data-center-rdimm-ddr5-tester"
				(path ""
					(page "13")
				)
			)
		)
	)
	(sheet
		(at 71.12 177.8)
		(size 38.1 19.05)
		(exclude_from_sim no)
		(in_bom yes)
		(on_board yes)
		(dnp no)
		(fields_autoplaced yes)
		(stroke
			(width 0.1524)
			(type solid)
		)
		(fill
			(color 0 0 0 0.0000)
		)
		(property "Sheetname" "I^{2}C + I3C"
			(at 71.12 177.0884 0)
			(effects
				(font
					(size 1.27 1.27)
				)
				(justify left bottom)
			)
		)
		(property "Sheetfile" "i2c.kicad_sch"
			(at 71.12 197.4346 0)
			(effects
				(font
					(size 1.27 1.27)
				)
				(justify left top)
			)
		)
		(pin "FPGA_DDR{I^{2}C}" bidirectional
			(at 109.22 193.04 0)
			(effects
				(font
					(size 1.27 1.27)
				)
				(justify right)
			)
		)
		(pin "FPGA_PWR{I^{2}C}" bidirectional
			(at 109.22 195.58 0)
			(effects
				(font
					(size 1.27 1.27)
				)
				(justify right)
			)
		)
		(pin "FTDI{I^{2}C}" bidirectional
			(at 109.22 180.34 0)
			(effects
				(font
					(size 1.27 1.27)
				)
				(justify right)
			)
		)
		(pin "PWR{I^{2}C}" bidirectional
			(at 71.12 194.31 180)
			(effects
				(font
					(size 1.27 1.27)
				)
				(justify left)
			)
		)
		(pin "DDR{I^{2}C}" bidirectional
			(at 71.12 180.34 180)
			(effects
				(font
					(size 1.27 1.27)
				)
				(justify left)
			)
		)
		(pin "FPGA_I3C{I^{2}C}" bidirectional
			(at 109.22 190.5 0)
			(effects
				(font
					(size 1.27 1.27)
				)
				(justify right)
			)
		)
		(instances
			(project "data-center-rdimm-ddr5-tester"
				(path ""
					(page "17")
				)
			)
		)
	)
	(sheet
		(at 71.12 209.55)
		(size 38.1 20.32)
		(exclude_from_sim no)
		(in_bom yes)
		(on_board yes)
		(dnp no)
		(fields_autoplaced yes)
		(stroke
			(width 0.1524)
			(type solid)
		)
		(fill
			(color 0 0 0 0.0000)
		)
		(property "Sheetname" "HDMI + SD Card"
			(at 71.12 208.8384 0)
			(effects
				(font
					(size 1.27 1.27)
				)
				(justify left bottom)
			)
		)
		(property "Sheetfile" "hdmi-sd-card.kicad_sch"
			(at 71.12 230.4546 0)
			(effects
				(font
					(size 1.27 1.27)
				)
				(justify left top)
			)
		)
		(pin "SD{SDIO}" bidirectional
			(at 109.22 226.06 0)
			(effects
				(font
					(size 1.27 1.27)
				)
				(justify right)
			)
		)
		(pin "HDMI_OUT{TMDS}" bidirectional
			(at 109.22 219.71 0)
			(effects
				(font
					(size 1.27 1.27)
				)
				(justify right)
			)
		)
		(pin "HDMI_IN{TMDS}" bidirectional
			(at 109.22 222.25 0)
			(effects
				(font
					(size 1.27 1.27)
				)
				(justify right)
			)
		)
		(pin "HDMI_CTL{I^{2}C}" bidirectional
			(at 109.22 217.17 0)
			(effects
				(font
					(size 1.27 1.27)
				)
				(justify right)
			)
		)
		(pin "HDMI_OUT_I2C{I^{2}C}" bidirectional
			(at 109.22 214.63 0)
			(effects
				(font
					(size 1.27 1.27)
				)
				(justify right)
			)
		)
		(pin "HDMI_IN_I2C{I^{2}C}" bidirectional
			(at 109.22 212.09 0)
			(effects
				(font
					(size 1.27 1.27)
				)
				(justify right)
			)
		)
		(instances
			(project "data-center-rdimm-ddr5-tester"
				(path ""
					(page "18")
				)
			)
		)
	)
	(sheet
		(at 234.95 146.05)
		(size 38.1 50.8)
		(exclude_from_sim no)
		(in_bom yes)
		(on_board yes)
		(dnp no)
		(fields_autoplaced yes)
		(stroke
			(width 0.1524)
			(type solid)
		)
		(fill
			(color 0 0 0 0.0000)
		)
		(property "Sheetname" "FPGA MGT Interface"
			(at 234.95 145.3384 0)
			(effects
				(font
					(size 1.27 1.27)
				)
				(justify left bottom)
			)
		)
		(property "Sheetfile" "fpga-mgt.kicad_sch"
			(at 234.95 197.4346 0)
			(effects
				(font
					(size 1.27 1.27)
				)
				(justify left top)
			)
		)
		(pin "PCIE{PCIe_x8}" bidirectional
			(at 273.05 194.31 0)
			(effects
				(font
					(size 1.27 1.27)
				)
				(justify right)
			)
		)
		(pin "HDMI_OUT{TMDS}" bidirectional
			(at 273.05 154.94 0)
			(effects
				(font
					(size 1.27 1.27)
				)
				(justify right)
			)
		)
		(pin "HDMI_IN{TMDS}" bidirectional
			(at 273.05 152.4 0)
			(effects
				(font
					(size 1.27 1.27)
				)
				(justify right)
			)
		)
		(pin "HDMI_CTL{I^{2}C}" bidirectional
			(at 273.05 157.48 0)
			(effects
				(font
					(size 1.27 1.27)
				)
				(justify right)
			)
		)
		(instances
			(project "data-center-rdimm-ddr5-tester"
				(path ""
					(page "11")
				)
			)
		)
	)
	(sheet
		(at 147.32 205.74)
		(size 127 19.05)
		(exclude_from_sim no)
		(in_bom yes)
		(on_board yes)
		(dnp no)
		(fields_autoplaced yes)
		(stroke
			(width 0.1524)
			(type solid)
		)
		(fill
			(color 0 0 0 0.0000)
		)
		(property "Sheetname" "PCIe connector"
			(at 147.32 205.0284 0)
			(effects
				(font
					(size 1.27 1.27)
				)
				(justify left bottom)
			)
		)
		(property "Sheetfile" "pcie-connector.kicad_sch"
			(at 147.32 225.3746 0)
			(effects
				(font
					(size 1.27 1.27)
				)
				(justify left top)
			)
		)
		(pin "PCIE{PCIe_x8}" tri_state
			(at 274.32 208.28 0)
			(effects
				(font
					(size 1.27 1.27)
				)
				(justify right)
			)
		)
		(instances
			(project "data-center-rdimm-ddr5-tester"
				(path ""
					(page "12")
				)
			)
		)
	)
	(sheet_instances
		(path "/"
			(page "1")
		)
	)
)
